# T6G (Grand Teton) — schematic netlist excerpt (pin names and nets, part order shuffled) for the footprints in the layout excerpt that follows; sources: Cadence DE-HDL packaged netlist, KiCad conversion of 04192023_DAF0TMB3IC0_F0TG_MB_C_brd_V02_OCP.brd

R4127  Q_RES  4.7K 5% CHIP  pkg 0402LF  page 125 : A = P3V3_AUX ; B = GPU_3V3IO_RSVD1_FFU_N
C2486  Q_CAP  22UF 4V 20% X6S  pkg C0402  page 74 : A = PVDD11_S3_P1 ; B = GND

(kicad_pcb
	(version 20260206)
	(generator "pcbnew")
	(generator_version "10.0")
	(general
		(thickness 1.6)
		(legacy_teardrops no)
	)
	(paper "A4")
	(title_block
		(title "04192023_DAF0TMB3IC0_F0TG_MB_C_brd_V02_OCP.brd")
		(comment 1 "Grand Teton / footprints 7016-7017 of 8354")
	)
	(layers
		(0 "F.Cu" signal "TOP")
		(4 "In1.Cu" signal "GND")
		(6 "In2.Cu" signal "IN1")
		(8 "In3.Cu" signal "GND1")
		(10 "In4.Cu" signal "IN2")
		(12 "In5.Cu" signal "GND2")
		(14 "In6.Cu" signal "IN3")
		(16 "In7.Cu" signal "GND3")
		(18 "In8.Cu" signal "VCC")
		(20 "In9.Cu" signal "VCC1")
		(22 "In10.Cu" signal "GND4")
		(24 "In11.Cu" signal "IN4")
		(26 "In12.Cu" signal "GND5")
		(28 "In13.Cu" signal "IN5")
		(30 "In14.Cu" signal "GND6")
		(32 "In15.Cu" signal "IN6")
		(34 "In16.Cu" signal "GND7")
		(2 "B.Cu" signal "BOTTOM")
		(9 "F.Adhes" user "F.Adhesive")
		(11 "B.Adhes" user "B.Adhesive")
		(13 "F.Paste" user "Package Geometry/Pastemask Top")
		(15 "B.Paste" user "Package Geometry/Pastemask Bottom")
		(5 "F.SilkS" user "Ref Des/Silkscreen Top")
		(7 "B.SilkS" user "Ref Des/Silkscreen Bottom")
		(1 "F.Mask" user "Board Geometry/Soldermask Top")
		(3 "B.Mask" user "Board Geometry/Soldermask Bottom")
		(17 "Dwgs.User" user "User.Drawings")
		(19 "Cmts.User" user "User.Comments")
		(21 "Eco1.User" user "User.Eco1")
		(23 "Eco2.User" user "User.Eco2")
		(25 "Edge.Cuts" user "Board Geometry/Outline")
		(27 "Margin" user)
		(31 "F.CrtYd" user "Package Geometry/Place Bound Top")
		(29 "B.CrtYd" user "Package Geometry/Place Bound Bottom")
		(35 "F.Fab" user "Ref Des/Assembly Top")
		(33 "B.Fab" user "Ref Des/Assembly Bottom")
	)
	(footprint ""
		(layer "B.Cu")
		(at 110.856014 -258.795266 180)
		(property "Reference" "C2486"
			(at 0 0 0)
			(layer "B.SilkS")
			(hide yes)
			(effects
				(font
					(size 1.27 1.27)
				)
				(justify mirror)
			)
		)
		(property "Value" ""
			(at 0 0 0)
			(layer "B.Fab")
			(effects
				(font
					(size 1.27 1.27)
				)
				(justify mirror)
			)
		)
		(duplicate_pad_numbers_are_jumpers no)
		(fp_line
			(start 0.7874 0.4064)
			(end 0.7874 -0.4064)
			(stroke
				(width 0.1524)
				(type default)
			)
			(layer "B.SilkS")
		)
		(fp_line
			(start 0.7874 -0.4064)
			(end -0.7874 -0.4064)
			(stroke
				(width 0.1524)
				(type default)
			)
			(layer "B.SilkS")
		)
		(fp_line
			(start -0.7874 0.4064)
			(end 0.7874 0.4064)
			(stroke
				(width 0.1524)
				(type default)
			)
			(layer "B.SilkS")
		)
		(fp_line
			(start -0.7874 -0.4064)
			(end -0.7874 0.4064)
			(stroke
				(width 0.1524)
				(type default)
			)
			(layer "B.SilkS")
		)
		(fp_line
			(start 0.67945 0.3048)
			(end 0.67945 -0.305054)
			(stroke
				(width 0.1)
				(type default)
			)
			(layer "B.Fab")
		)
		(fp_line
			(start 0.67945 -0.305054)
			(end 0.12065 -0.305054)
			(stroke
				(width 0.1)
				(type default)
			)
			(layer "B.Fab")
		)
		(fp_line
			(start 0.12065 0.3048)
			(end 0.67945 0.3048)
			(stroke
				(width 0.1)
				(type default)
			)
			(layer "B.Fab")
		)
		(fp_line
			(start 0.12065 0.2794)
			(end 0.12065 0.3048)
			(stroke
				(width 0.1)
				(type default)
			)
			(layer "B.Fab")
		)
		(fp_line
			(start 0.12065 -0.2794)
			(end -0.12065 -0.2794)
			(stroke
				(width 0.1)
				(type default)
			)
			(layer "B.Fab")
		)
		(fp_line
			(start 0.12065 -0.305054)
			(end 0.12065 -0.2794)
			(stroke
				(width 0.1)
				(type default)
			)
			(layer "B.Fab")
		)
		(fp_line
			(start -0.120396 0.3048)
			(end -0.120396 0.2794)
			(stroke
				(width 0.1)
				(type default)
			)
			(layer "B.Fab")
		)
		(fp_line
			(start -0.120396 0.2794)
			(end 0.12065 0.2794)
			(stroke
				(width 0.1)
				(type default)
			)
			(layer "B.Fab")
		)
		(fp_line
			(start -0.12065 -0.2794)
			(end -0.12065 -0.3048)
			(stroke
				(width 0.1)
				(type default)
			)
			(layer "B.Fab")
		)
		(fp_line
			(start -0.12065 -0.3048)
			(end -0.67945 -0.3048)
			(stroke
				(width 0.1)
				(type default)
			)
			(layer "B.Fab")
		)
		(fp_line
			(start -0.67945 0.3048)
			(end -0.120396 0.3048)
			(stroke
				(width 0.1)
				(type default)
			)
			(layer "B.Fab")
		)
		(fp_line
			(start -0.67945 -0.3048)
			(end -0.67945 0.3048)
			(stroke
				(width 0.1)
				(type default)
			)
			(layer "B.Fab")
		)
		(pad "1" smd circle
			(at 0.40005 0)
			(size 0 0)
			(layers "B.Cu" "B.Mask" "B.Paste")
			(net "PVDD11_S3_P1")
		)
		(pad "2" smd circle
			(at -0.40005 0)
			(size 0 0)
			(layers "B.Cu" "B.Mask" "B.Paste")
			(net "GND")
		)
	)
	(footprint ""
		(layer "B.Cu")
		(at 170.1292 -431.841656)
		(property "Reference" "R4127"
			(at 0 0 0)
			(layer "B.SilkS")
			(hide yes)
			(effects
				(font
					(size 1.27 1.27)
				)
				(justify mirror)
			)
		)
		(property "Value" ""
			(at 0 0 0)
			(layer "B.Fab")
			(effects
				(font
					(size 1.27 1.27)
				)
				(justify mirror)
			)
		)
		(duplicate_pad_numbers_are_jumpers no)
		(fp_line
			(start -0.7874 -0.4064)
			(end -0.7874 0.4064)
			(stroke
				(width 0.1524)
				(type default)
			)
			(layer "B.SilkS")
		)
		(fp_line
			(start -0.7874 0.4064)
			(end 0.7874 0.4064)
			(stroke
				(width 0.1524)
				(type default)
			)
			(layer "B.SilkS")
		)
		(fp_line
			(start 0.7874 -0.4064)
			(end -0.7874 -0.4064)
			(stroke
				(width 0.1524)
				(type default)
			)
			(layer "B.SilkS")
		)
		(fp_line
			(start 0.7874 0.4064)
			(end 0.7874 -0.4064)
			(stroke
				(width 0.1524)
				(type default)
			)
			(layer "B.SilkS")
		)
		(fp_line
			(start -0.67945 -0.3048)
			(end -0.67945 0.3048)
			(stroke
				(width 0.1)
				(type default)
			)
			(layer "B.Fab")
		)
		(fp_line
			(start -0.67945 0.3048)
			(end -0.120396 0.3048)
			(stroke
				(width 0.1)
				(type default)
			)
			(layer "B.Fab")
		)
		(fp_line
			(start -0.12065 -0.3048)
			(end -0.67945 -0.3048)
			(stroke
				(width 0.1)
				(type default)
			)
			(layer "B.Fab")
		)
		(fp_line
			(start -0.12065 -0.2794)
			(end -0.12065 -0.3048)
			(stroke
				(width 0.1)
				(type default)
			)
			(layer "B.Fab")
		)
		(fp_line
			(start -0.120396 0.2794)
			(end 0.12065 0.2794)
			(stroke
				(width 0.1)
				(type default)
			)
			(layer "B.Fab")
		)
		(fp_line
			(start -0.120396 0.3048)
			(end -0.120396 0.2794)
			(stroke
				(width 0.1)
				(type default)
			)
			(layer "B.Fab")
		)
		(fp_line
			(start 0.12065 -0.305054)
			(end 0.12065 -0.2794)
			(stroke
				(width 0.1)
				(type default)
			)
			(layer "B.Fab")
		)
		(fp_line
			(start 0.12065 -0.2794)
			(end -0.12065 -0.2794)
			(stroke
				(width 0.1)
				(type default)
			)
			(layer "B.Fab")
		)
		(fp_line
			(start 0.12065 0.2794)
			(end 0.12065 0.3048)
			(stroke
				(width 0.1)
				(type default)
			)
			(layer "B.Fab")
		)
		(fp_line
			(start 0.12065 0.3048)
			(end 0.67945 0.3048)
			(stroke
				(width 0.1)
				(type default)
			)
			(layer "B.Fab")
		)
		(fp_line
			(start 0.67945 -0.305054)
			(end 0.12065 -0.305054)
			(stroke
				(width 0.1)
				(type default)
			)
			(layer "B.Fab")
		)
		(fp_line
			(start 0.67945 0.3048)
			(end 0.67945 -0.305054)
			(stroke
				(width 0.1)
				(type default)
			)
			(layer "B.Fab")
		)
		(pad "1" smd circle
			(at 0.40005 0 180)
			(size 0 0)
			(layers "B.Cu" "B.Mask" "B.Paste")
			(net "P3V3_AUX")
		)
		(pad "2" smd circle
			(at -0.40005 0 180)
			(size 0 0)
			(layers "B.Cu" "B.Mask" "B.Paste")
			(net "GPU_3V3IO_RSVD1_FFU_N")
		)
	)
)
